(kicad_pcb
	(version 20260206)
	(generator "pcbnew")
	(generator_version "10.0")
	(general
		(thickness 1.6)
		(legacy_teardrops no)
	)
	(paper "A4")
	(title_block
		(title "panther-plus-userver — 13130-1b_20150205.brd")
		(comment 1 "Honey Badger (Wiwynn) / footprints 435-442 of 1509")
	)
	(layers
		(0 "F.Cu" signal "TOP")
		(4 "In1.Cu" signal "L2")
		(6 "In2.Cu" signal "L3")
		(8 "In3.Cu" signal "L4")
		(10 "In4.Cu" signal "L5")
		(12 "In5.Cu" signal "L6")
		(14 "In6.Cu" signal "L7")
		(16 "In7.Cu" signal "L8")
		(18 "In8.Cu" signal "L9")
		(20 "In9.Cu" signal "L10")
		(22 "In10.Cu" signal "L11")
		(2 "B.Cu" signal "BOTTOM")
		(9 "F.Adhes" user "F.Adhesive")
		(11 "B.Adhes" user "B.Adhesive")
		(13 "F.Paste" user "Package Geometry/Pastemask Top")
		(15 "B.Paste" user "Package Geometry/Pastemask Bottom")
		(5 "F.SilkS" user "Ref Des/Silkscreen Top")
		(7 "B.SilkS" user "Ref Des/Silkscreen Bottom")
		(1 "F.Mask" user "Board Geometry/Soldermask Top")
		(3 "B.Mask" user "Board Geometry/Soldermask Bottom")
		(17 "Dwgs.User" user "User.Drawings")
		(19 "Cmts.User" user "User.Comments")
		(21 "Eco1.User" user "User.Eco1")
		(23 "Eco2.User" user "User.Eco2")
		(25 "Edge.Cuts" user "Board Geometry/Outline")
		(27 "Margin" user)
		(31 "F.CrtYd" user "Package Geometry/Place Bound Top")
		(29 "B.CrtYd" user "Package Geometry/Place Bound Bottom")
		(35 "F.Fab" user "Ref Des/Assembly Top")
		(33 "B.Fab" user "Ref Des/Assembly Bottom")
	)
	(footprint ""
		(layer "F.Cu")
		(at 74.041 -47.117 -90)
		(property "Reference" "R84"
			(at 0 0 270)
			(layer "F.SilkS")
			(hide yes)
			(effects
				(font
					(size 1.27 1.27)
				)
			)
		)
		(property "Value" "0R2J-2-GP"
			(at 0.064008 -3.993896 270)
			(unlocked yes)
			(layer "F.Fab")
			(hide yes)
			(effects
				(font
					(size 1.016 1.016)
					(thickness 0.1524)
				)
			)
		)
		(property "Device Type" "R402H16"
			(at 0.064008 -5.517896 270)
			(unlocked yes)
			(layer "F.Fab")
			(hide yes)
			(effects
				(font
					(size 1.016 1.016)
					(thickness 0.1524)
				)
			)
		)
		(duplicate_pad_numbers_are_jumpers no)
		(fp_rect
			(start -0.381 0.8382)
			(end 0.381 -0.8382)
			(stroke
				(width 0)
				(type default)
			)
			(fill no)
			(layer "F.CrtYd")
		)
		(fp_rect
			(start -0.381 0.8382)
			(end 0.381 -0.8382)
			(stroke
				(width 0)
				(type default)
			)
			(fill no)
			(layer "F.Fab")
		)
		(pad "1" smd custom
			(at 0 -0.4318 270)
			(size 0.127 0.127)
			(layers "F.Cu" "F.Mask" "F.Paste")
			(net "SMB_CLK1_SPKR")
			(options
				(clearance outline)
				(anchor circle)
			)
			(primitives
				(gr_poly
					(pts
						(arc
							(start -0.2032 -0.2794)
							(mid -0.239121 -0.264521)
							(end -0.254 -0.2286)
						)
						(arc
							(start -0.254 0.2286)
							(mid -0.239121 0.264521)
							(end -0.2032 0.2794)
						)
						(arc
							(start 0.2032 0.2794)
							(mid 0.239121 0.264521)
							(end 0.254 0.2286)
						)
						(arc
							(start 0.254 -0.2286)
							(mid 0.239121 -0.264521)
							(end 0.2032 -0.2794)
						)
					)
					(width 0)
					(fill yes)
				)
			)
		)
		(pad "2" smd custom
			(at 0 0.4318 270)
			(size 0.127 0.127)
			(layers "F.Cu" "F.Mask" "F.Paste")
			(net "CPU_BEEP_LED")
			(options
				(clearance outline)
				(anchor circle)
			)
			(primitives
				(gr_poly
					(pts
						(arc
							(start -0.2032 -0.2794)
							(mid -0.239121 -0.264521)
							(end -0.254 -0.2286)
						)
						(arc
							(start -0.254 0.2286)
							(mid -0.239121 0.264521)
							(end -0.2032 0.2794)
						)
						(arc
							(start 0.2032 0.2794)
							(mid 0.239121 0.264521)
							(end 0.254 0.2286)
						)
						(arc
							(start 0.254 -0.2286)
							(mid 0.239121 -0.264521)
							(end 0.2032 -0.2794)
						)
					)
					(width 0)
					(fill yes)
				)
			)
		)
	)
	(footprint ""
		(layer "F.Cu")
		(at 155.575 -55.372)
		(property "Reference" "R290"
			(at 0 0 0)
			(layer "F.SilkS")
			(hide yes)
			(effects
				(font
					(size 1.27 1.27)
				)
			)
		)
		(property "Value" "33R2F-3-GP"
			(at 1.7907 -1.1176 0)
			(unlocked yes)
			(layer "F.Fab")
			(hide yes)
			(effects
				(font
					(size 1.016 1.016)
					(thickness 0.1524)
				)
			)
		)
		(property "Device Type" "R402H16"
			(at 1.7907 -2.6416 0)
			(unlocked yes)
			(layer "F.Fab")
			(hide yes)
			(effects
				(font
					(size 1.016 1.016)
					(thickness 0.1524)
				)
			)
		)
		(duplicate_pad_numbers_are_jumpers no)
		(fp_rect
			(start -0.381 0.8382)
			(end 0.381 -0.8382)
			(stroke
				(width 0)
				(type default)
			)
			(fill no)
			(layer "F.CrtYd")
		)
		(fp_rect
			(start -0.381 0.8382)
			(end 0.381 -0.8382)
			(stroke
				(width 0)
				(type default)
			)
			(fill no)
			(layer "F.Fab")
		)
		(pad "1" smd custom
			(at 0 -0.4318)
			(size 0.127 0.127)
			(layers "F.Cu" "F.Mask" "F.Paste")
			(net "C_R_ASDO")
			(options
				(clearance outline)
				(anchor circle)
			)
			(primitives
				(gr_poly
					(pts
						(arc
							(start -0.2032 -0.2794)
							(mid -0.239121 -0.264521)
							(end -0.254 -0.2286)
						)
						(arc
							(start -0.254 0.2286)
							(mid -0.239121 0.264521)
							(end -0.2032 0.2794)
						)
						(arc
							(start 0.2032 0.2794)
							(mid 0.239121 0.264521)
							(end 0.254 0.2286)
						)
						(arc
							(start 0.254 -0.2286)
							(mid 0.239121 -0.264521)
							(end 0.2032 -0.2794)
						)
					)
					(width 0)
					(fill yes)
				)
			)
		)
		(pad "2" smd custom
			(at 0 0.4318)
			(size 0.127 0.127)
			(layers "F.Cu" "F.Mask" "F.Paste")
			(net "C_ASDO")
			(options
				(clearance outline)
				(anchor circle)
			)
			(primitives
				(gr_poly
					(pts
						(arc
							(start -0.2032 -0.2794)
							(mid -0.239121 -0.264521)
							(end -0.254 -0.2286)
						)
						(arc
							(start -0.254 0.2286)
							(mid -0.239121 0.264521)
							(end -0.2032 0.2794)
						)
						(arc
							(start 0.2032 0.2794)
							(mid 0.239121 0.264521)
							(end 0.254 0.2286)
						)
						(arc
							(start 0.254 -0.2286)
							(mid 0.239121 -0.264521)
							(end 0.2032 -0.2794)
						)
					)
					(width 0)
					(fill yes)
				)
			)
		)
	)
	(footprint ""
		(layer "F.Cu")
		(at 31.0896 -60.9346 -90)
		(property "Reference" "PC6"
			(at 0 0 270)
			(layer "F.SilkS")
			(hide yes)
			(effects
				(font
					(size 1.27 1.27)
				)
			)
		)
		(property "Value" "SC47U16V0MX-GP"
			(at -2.3368 -3.5052 270)
			(unlocked yes)
			(layer "F.Fab")
			(hide yes)
			(effects
				(font
					(size 1.016 1.016)
					(thickness 0.1524)
				)
			)
		)
		(property "Device Type" "C1210H107"
			(at -2.3368 -5.0292 270)
			(unlocked yes)
			(layer "F.Fab")
			(hide yes)
			(effects
				(font
					(size 1.016 1.016)
					(thickness 0.1524)
				)
			)
		)
		(duplicate_pad_numbers_are_jumpers no)
		(fp_rect
			(start -1.4986 1.9685)
			(end 1.4986 -1.9685)
			(stroke
				(width 0)
				(type default)
			)
			(fill no)
			(layer "F.CrtYd")
		)
		(fp_rect
			(start -1.4986 1.9685)
			(end 1.4986 -1.9685)
			(stroke
				(width 0)
				(type default)
			)
			(fill no)
			(layer "F.Fab")
		)
		(pad "1" smd rect
			(at 0 -1.2446 270)
			(size 2.7432 1.1938)
			(layers "F.Cu" "F.Mask" "F.Paste")
			(net "VR_FET_SW_P12V_PVCCP_PVNN")
		)
		(pad "2" smd rect
			(at 0 1.2446 270)
			(size 2.7432 1.1938)
			(layers "F.Cu" "F.Mask" "F.Paste")
			(net "GND")
		)
	)
	(footprint ""
		(layer "F.Cu")
		(at 71.882 -19.939 90)
		(property "Reference" "U32"
			(at 0 0 90)
			(layer "F.SilkS")
			(hide yes)
			(effects
				(font
					(size 1.27 1.27)
				)
			)
		)
		(property "Value" "2N7002DW-7F-GP"
			(at -2.5654 1.1049 90)
			(unlocked yes)
			(layer "F.Fab")
			(hide yes)
			(effects
				(font
					(size 1.016 1.016)
					(thickness 0.1524)
				)
			)
		)
		(property "Device Type" "SOT-363H44"
			(at -2.5654 -0.4191 90)
			(unlocked yes)
			(layer "F.Fab")
			(hide yes)
			(effects
				(font
					(size 1.016 1.016)
					(thickness 0.1524)
				)
			)
		)
		(duplicate_pad_numbers_are_jumpers no)
		(fp_poly
			(pts
				(xy -0.6731 1.4351) (xy -0.9779 1.7399) (xy -0.381 1.7399) (xy -0.3683 1.7399) (xy -0.381 1.7272)
			)
			(stroke
				(width 0)
				(type default)
			)
			(fill yes)
			(layer "F.SilkS")
		)
		(fp_poly
			(pts
				(xy 1.2573 0.8763) (xy 1.2573 -0.8763) (xy 0.9525 -0.8763) (xy 0.9525 -1.4351) (xy -0.9525 -1.4351)
				(xy -0.9525 -0.8763) (xy -1.2573 -0.8763) (xy -1.2573 0.8763) (xy -0.9525 0.8763) (xy -0.9525 1.4351)
				(xy 0.9525 1.4351) (xy 0.9525 0.8763)
			)
			(stroke
				(width 0)
				(type default)
			)
			(fill no)
			(layer "F.CrtYd")
		)
		(fp_poly
			(pts
				(xy 1.2573 0.8763) (xy 1.2573 -0.8763) (xy 0.9525 -0.8763) (xy 0.9525 -1.4351) (xy -0.9525 -1.4351)
				(xy -0.9525 -0.8763) (xy -1.2573 -0.8763) (xy -1.2573 0.8763) (xy -0.9525 0.8763) (xy -0.9525 1.4351)
				(xy 0.9525 1.4351) (xy 0.9525 0.8763)
			)
			(stroke
				(width 0)
				(type default)
			)
			(fill no)
			(layer "F.Fab")
		)
		(pad "1" smd rect
			(at -0.65024 0.8255 90)
			(size 0.3556 0.9652)
			(layers "F.Cu" "F.Mask" "F.Paste")
			(net "CPU_TXD")
		)
		(pad "2" smd rect
			(at 0 0.8255 90)
			(size 0.3556 0.9652)
			(layers "F.Cu" "F.Mask" "F.Paste")
			(net "PMU_BUF_PLTRST#")
		)
		(pad "3" smd rect
			(at 0.65024 0.8255 90)
			(size 0.3556 0.9652)
			(layers "F.Cu" "F.Mask" "F.Paste")
			(net "GF_CPU_RXD")
		)
		(pad "4" smd rect
			(at 0.65024 -0.8255 90)
			(size 0.3556 0.9652)
			(layers "F.Cu" "F.Mask" "F.Paste")
			(net "CPU_RXD")
		)
		(pad "5" smd rect
			(at 0 -0.8255 90)
			(size 0.3556 0.9652)
			(layers "F.Cu" "F.Mask" "F.Paste")
			(net "PMU_BUF_PLTRST#")
		)
		(pad "6" smd rect
			(at -0.65024 -0.8255 90)
			(size 0.3556 0.9652)
			(layers "F.Cu" "F.Mask" "F.Paste")
			(net "GF_CPU_TXD")
		)
	)
	(footprint ""
		(layer "F.Cu")
		(at 15.8496 -56.8452 -90)
		(property "Reference" "PR57"
			(at 0 0 270)
			(layer "F.SilkS")
			(hide yes)
			(effects
				(font
					(size 1.27 1.27)
				)
			)
		)
		(property "Value" "10KR2F-2-GP"
			(at 1.7907 -1.1176 270)
			(unlocked yes)
			(layer "F.Fab")
			(hide yes)
			(effects
				(font
					(size 1.016 1.016)
					(thickness 0.1524)
				)
			)
		)
		(property "Device Type" "R402H16"
			(at 1.7907 -2.6416 270)
			(unlocked yes)
			(layer "F.Fab")
			(hide yes)
			(effects
				(font
					(size 1.016 1.016)
					(thickness 0.1524)
				)
			)
		)
		(duplicate_pad_numbers_are_jumpers no)
		(fp_rect
			(start -0.381 0.8382)
			(end 0.381 -0.8382)
			(stroke
				(width 0)
				(type default)
			)
			(fill no)
			(layer "F.CrtYd")
		)
		(fp_rect
			(start -0.381 0.8382)
			(end 0.381 -0.8382)
			(stroke
				(width 0)
				(type default)
			)
			(fill no)
			(layer "F.Fab")
		)
		(pad "1" smd custom
			(at 0 -0.4318 270)
			(size 0.127 0.127)
			(layers "F.Cu" "F.Mask" "F.Paste")
			(net "PVCC_PVNN_EN_R")
			(options
				(clearance outline)
				(anchor circle)
			)
			(primitives
				(gr_poly
					(pts
						(arc
							(start -0.2032 -0.2794)
							(mid -0.239121 -0.264521)
							(end -0.254 -0.2286)
						)
						(arc
							(start -0.254 0.2286)
							(mid -0.239121 0.264521)
							(end -0.2032 0.2794)
						)
						(arc
							(start 0.2032 0.2794)
							(mid 0.239121 0.264521)
							(end 0.254 0.2286)
						)
						(arc
							(start 0.254 -0.2286)
							(mid 0.239121 -0.264521)
							(end 0.2032 -0.2794)
						)
					)
					(width 0)
					(fill yes)
				)
			)
		)
		(pad "2" smd custom
			(at 0 0.4318 270)
			(size 0.127 0.127)
			(layers "F.Cu" "F.Mask" "F.Paste")
			(net "P3V3_STBY")
			(options
				(clearance outline)
				(anchor circle)
			)
			(primitives
				(gr_poly
					(pts
						(arc
							(start -0.2032 -0.2794)
							(mid -0.239121 -0.264521)
							(end -0.254 -0.2286)
						)
						(arc
							(start -0.254 0.2286)
							(mid -0.239121 0.264521)
							(end -0.2032 0.2794)
						)
						(arc
							(start 0.2032 0.2794)
							(mid 0.239121 0.264521)
							(end 0.254 0.2286)
						)
						(arc
							(start 0.254 -0.2286)
							(mid 0.239121 -0.264521)
							(end 0.2032 -0.2794)
						)
					)
					(width 0)
					(fill yes)
				)
			)
		)
	)
	(footprint ""
		(layer "F.Cu")
		(at 68.3768 -58.9534 90)
		(property "Reference" "R146"
			(at 0 0 90)
			(layer "F.SilkS")
			(hide yes)
			(effects
				(font
					(size 1.27 1.27)
				)
			)
		)
		(property "Value" "10KR2F-2-GP"
			(at 1.7907 -1.1176 90)
			(unlocked yes)
			(layer "F.Fab")
			(hide yes)
			(effects
				(font
					(size 1.016 1.016)
					(thickness 0.1524)
				)
			)
		)
		(property "Device Type" "R402H16"
			(at 1.7907 -2.6416 90)
			(unlocked yes)
			(layer "F.Fab")
			(hide yes)
			(effects
				(font
					(size 1.016 1.016)
					(thickness 0.1524)
				)
			)
		)
		(duplicate_pad_numbers_are_jumpers no)
		(fp_rect
			(start -0.381 0.8382)
			(end 0.381 -0.8382)
			(stroke
				(width 0)
				(type default)
			)
			(fill no)
			(layer "F.CrtYd")
		)
		(fp_rect
			(start -0.381 0.8382)
			(end 0.381 -0.8382)
			(stroke
				(width 0)
				(type default)
			)
			(fill no)
			(layer "F.Fab")
		)
		(pad "1" smd custom
			(at 0 -0.4318 90)
			(size 0.127 0.127)
			(layers "F.Cu" "F.Mask" "F.Paste")
			(net "P3V3")
			(options
				(clearance outline)
				(anchor circle)
			)
			(primitives
				(gr_poly
					(pts
						(arc
							(start -0.2032 -0.2794)
							(mid -0.239121 -0.264521)
							(end -0.254 -0.2286)
						)
						(arc
							(start -0.254 0.2286)
							(mid -0.239121 0.264521)
							(end -0.2032 0.2794)
						)
						(arc
							(start 0.2032 0.2794)
							(mid 0.239121 0.264521)
							(end 0.254 0.2286)
						)
						(arc
							(start 0.254 -0.2286)
							(mid 0.239121 -0.264521)
							(end 0.2032 -0.2794)
						)
					)
					(width 0)
					(fill yes)
				)
			)
		)
		(pad "2" smd custom
			(at 0 0.4318 90)
			(size 0.127 0.127)
			(layers "F.Cu" "F.Mask" "F.Paste")
			(net "P3V3_SENSE")
			(options
				(clearance outline)
				(anchor circle)
			)
			(primitives
				(gr_poly
					(pts
						(arc
							(start -0.2032 -0.2794)
							(mid -0.239121 -0.264521)
							(end -0.254 -0.2286)
						)
						(arc
							(start -0.254 0.2286)
							(mid -0.239121 0.264521)
							(end -0.2032 0.2794)
						)
						(arc
							(start 0.2032 0.2794)
							(mid 0.239121 0.264521)
							(end 0.254 0.2286)
						)
						(arc
							(start 0.254 -0.2286)
							(mid 0.239121 -0.264521)
							(end 0.2032 -0.2794)
						)
					)
					(width 0)
					(fill yes)
				)
			)
		)
	)
	(footprint ""
		(layer "F.Cu")
		(at 204.597 -35.56 180)
		(property "Reference" "PC82"
			(at 0 0 180)
			(layer "F.SilkS")
			(hide yes)
			(effects
				(font
					(size 1.27 1.27)
				)
			)
		)
		(property "Value" "SCD1U25V2KX-2-GP"
			(at 1.8923 -1.2065 180)
			(unlocked yes)
			(layer "F.Fab")
			(hide yes)
			(effects
				(font
					(size 1.016 1.016)
					(thickness 0.1524)
				)
			)
		)
		(property "Device Type" "C402H22"
			(at 1.8923 -2.7305 180)
			(unlocked yes)
			(layer "F.Fab")
			(hide yes)
			(effects
				(font
					(size 1.016 1.016)
					(thickness 0.1524)
				)
			)
		)
		(duplicate_pad_numbers_are_jumpers no)
		(fp_rect
			(start -0.381 0.7366)
			(end 0.381 -0.7366)
			(stroke
				(width 0)
				(type default)
			)
			(fill no)
			(layer "F.CrtYd")
		)
		(fp_rect
			(start -0.381 0.7366)
			(end 0.381 -0.7366)
			(stroke
				(width 0)
				(type default)
			)
			(fill no)
			(layer "F.Fab")
		)
		(pad "1" smd custom
			(at 0 -0.4572 180)
			(size 0.1143 0.1143)
			(layers "F.Cu" "F.Mask" "F.Paste")
			(net "PVDDR_VIN")
			(options
				(clearance outline)
				(anchor circle)
			)
			(primitives
				(gr_poly
					(pts
						(arc
							(start -0.254 -0.1778)
							(mid -0.239121 -0.213721)
							(end -0.2032 -0.2286)
						)
						(arc
							(start 0.2032 -0.2286)
							(mid 0.239121 -0.213721)
							(end 0.254 -0.1778)
						)
						(arc
							(start 0.254 0.1778)
							(mid 0.239121 0.213721)
							(end 0.2032 0.2286)
						)
						(arc
							(start -0.2032 0.2286)
							(mid -0.239121 0.213721)
							(end -0.254 0.1778)
						)
					)
					(width 0)
					(fill yes)
				)
			)
		)
		(pad "2" smd custom
			(at 0 0.4572 180)
			(size 0.1143 0.1143)
			(layers "F.Cu" "F.Mask" "F.Paste")
			(net "GND")
			(options
				(clearance outline)
				(anchor circle)
			)
			(primitives
				(gr_poly
					(pts
						(arc
							(start -0.254 -0.1778)
							(mid -0.239121 -0.213721)
							(end -0.2032 -0.2286)
						)
						(arc
							(start 0.2032 -0.2286)
							(mid 0.239121 -0.213721)
							(end 0.254 -0.1778)
						)
						(arc
							(start 0.254 0.1778)
							(mid 0.239121 0.213721)
							(end 0.2032 0.2286)
						)
						(arc
							(start -0.2032 0.2286)
							(mid -0.239121 0.213721)
							(end -0.254 0.1778)
						)
					)
					(width 0)
					(fill yes)
				)
			)
		)
	)
	(footprint ""
		(layer "F.Cu")
		(at 74.168 -43.307 90)
		(property "Reference" "R73"
			(at 0 0 90)
			(layer "F.SilkS")
			(hide yes)
			(effects
				(font
					(size 1.27 1.27)
				)
			)
		)
		(property "Value" "4K7R2F-GP"
			(at 0.064008 -3.993896 90)
			(unlocked yes)
			(layer "F.Fab")
			(hide yes)
			(effects
				(font
					(size 1.016 1.016)
					(thickness 0.1524)
				)
			)
		)
		(property "Device Type" "R402H16"
			(at 0.064008 -5.517896 90)
			(unlocked yes)
			(layer "F.Fab")
			(hide yes)
			(effects
				(font
					(size 1.016 1.016)
					(thickness 0.1524)
				)
			)
		)
		(duplicate_pad_numbers_are_jumpers no)
		(fp_rect
			(start -0.381 0.8382)
			(end 0.381 -0.8382)
			(stroke
				(width 0)
				(type default)
			)
			(fill no)
			(layer "F.CrtYd")
		)
		(fp_rect
			(start -0.381 0.8382)
			(end 0.381 -0.8382)
			(stroke
				(width 0)
				(type default)
			)
			(fill no)
			(layer "F.Fab")
		)
		(pad "1" smd custom
			(at 0 -0.4318 90)
			(size 0.127 0.127)
			(layers "F.Cu" "F.Mask" "F.Paste")
			(net "P3V3")
			(options
				(clearance outline)
				(anchor circle)
			)
			(primitives
				(gr_poly
					(pts
						(arc
							(start -0.2032 -0.2794)
							(mid -0.239121 -0.264521)
							(end -0.254 -0.2286)
						)
						(arc
							(start -0.254 0.2286)
							(mid -0.239121 0.264521)
							(end -0.2032 0.2794)
						)
						(arc
							(start 0.2032 0.2794)
							(mid 0.239121 0.264521)
							(end 0.254 0.2286)
						)
						(arc
							(start 0.254 -0.2286)
							(mid 0.239121 -0.264521)
							(end 0.2032 -0.2794)
						)
					)
					(width 0)
					(fill yes)
				)
			)
		)
		(pad "2" smd custom
			(at 0 0.4318 90)
			(size 0.127 0.127)
			(layers "F.Cu" "F.Mask" "F.Paste")
			(net "CPU_ERR_N0")
			(options
				(clearance outline)
				(anchor circle)
			)
			(primitives
				(gr_poly
					(pts
						(arc
							(start -0.2032 -0.2794)
							(mid -0.239121 -0.264521)
							(end -0.254 -0.2286)
						)
						(arc
							(start -0.254 0.2286)
							(mid -0.239121 0.264521)
							(end -0.2032 0.2794)
						)
						(arc
							(start 0.2032 0.2794)
							(mid 0.239121 0.264521)
							(end 0.254 0.2286)
						)
						(arc
							(start 0.254 -0.2286)
							(mid 0.239121 -0.264521)
							(end 0.2032 -0.2794)
						)
					)
					(width 0)
					(fill yes)
				)
			)
		)
	)
)
